(kicad_pcb
	(version 20260206)
	(generator "pcbnew")
	(generator_version "10.0")
	(general
		(thickness 1.6)
		(legacy_teardrops no)
	)
	(paper "A4")
	(title_block
		(title "Bryce Canyon_IOM_IOC_16318-2_OCP.brd")
		(comment 1 "Bryce Canyon / footprints 157-163 of 1605")
	)
	(layers
		(0 "F.Cu" signal "TOP")
		(4 "In1.Cu" signal "L2GND")
		(6 "In2.Cu" signal "L3")
		(8 "In3.Cu" signal "L4VCC")
		(10 "In4.Cu" signal "L5VCC")
		(12 "In5.Cu" signal "L6")
		(14 "In6.Cu" signal "L7GND")
		(2 "B.Cu" signal "BOTTOM")
		(9 "F.Adhes" user "F.Adhesive")
		(11 "B.Adhes" user "B.Adhesive")
		(13 "F.Paste" user "Package Geometry/Pastemask Top")
		(15 "B.Paste" user "Package Geometry/Pastemask Bottom")
		(5 "F.SilkS" user "Ref Des/Silkscreen Top")
		(7 "B.SilkS" user "Ref Des/Silkscreen Bottom")
		(1 "F.Mask" user "Board Geometry/Soldermask Top")
		(3 "B.Mask" user "Board Geometry/Soldermask Bottom")
		(17 "Dwgs.User" user "User.Drawings")
		(19 "Cmts.User" user "User.Comments")
		(21 "Eco1.User" user "User.Eco1")
		(23 "Eco2.User" user "User.Eco2")
		(25 "Edge.Cuts" user "Board Geometry/Outline")
		(27 "Margin" user)
		(31 "F.CrtYd" user "Package Geometry/Place Bound Top")
		(29 "B.CrtYd" user "Package Geometry/Place Bound Bottom")
		(35 "F.Fab" user "Ref Des/Assembly Top")
		(33 "B.Fab" user "Ref Des/Assembly Bottom")
	)
	(footprint ""
		(layer "F.Cu")
		(at 68.7324 -162.306 90)
		(property "Reference" "C52"
			(at 0 0 90)
			(layer "F.SilkS")
			(hide yes)
			(effects
				(font
					(size 1.27 1.27)
				)
			)
		)
		(property "Value" "SCD1U16V2KX-3GP"
			(at 1.1811 -2.7051 90)
			(unlocked yes)
			(layer "F.Fab")
			(hide yes)
			(effects
				(font
					(size 1.016 1.016)
					(thickness 0.1524)
				)
			)
		)
		(property "Device Type" "C402H22"
			(at 1.1811 -4.2291 90)
			(unlocked yes)
			(layer "F.Fab")
			(hide yes)
			(effects
				(font
					(size 1.016 1.016)
					(thickness 0.1524)
				)
			)
		)
		(duplicate_pad_numbers_are_jumpers no)
		(fp_rect
			(start -0.4318 0.9525)
			(end 0.4318 -0.9525)
			(stroke
				(width 0)
				(type default)
			)
			(fill no)
			(layer "F.CrtYd")
		)
		(fp_rect
			(start -0.4318 0.9525)
			(end 0.4318 -0.9525)
			(stroke
				(width 0)
				(type default)
			)
			(fill no)
			(layer "F.Fab")
		)
		(pad "1" smd custom
			(at 0 -0.4445 90)
			(size 0.1524 0.1524)
			(layers "F.Cu" "F.Mask" "F.Paste")
			(net "BMC_TPM_RST_N")
			(options
				(clearance outline)
				(anchor circle)
			)
			(primitives
				(gr_poly
					(pts
						(arc
							(start 0.3048 -0.2032)
							(mid 0.275042 -0.275042)
							(end 0.2032 -0.3048)
						)
						(arc
							(start -0.2032 -0.3048)
							(mid -0.275042 -0.275042)
							(end -0.3048 -0.2032)
						)
						(arc
							(start -0.3048 0.2032)
							(mid -0.275042 0.275042)
							(end -0.2032 0.3048)
						)
						(arc
							(start 0.2032 0.3048)
							(mid 0.275042 0.275042)
							(end 0.3048 0.2032)
						)
					)
					(width 0)
					(fill yes)
				)
			)
		)
		(pad "2" smd custom
			(at 0 0.4445 90)
			(size 0.1524 0.1524)
			(layers "F.Cu" "F.Mask" "F.Paste")
			(net "GND")
			(options
				(clearance outline)
				(anchor circle)
			)
			(primitives
				(gr_poly
					(pts
						(arc
							(start 0.3048 -0.2032)
							(mid 0.275042 -0.275042)
							(end 0.2032 -0.3048)
						)
						(arc
							(start -0.2032 -0.3048)
							(mid -0.275042 -0.275042)
							(end -0.3048 -0.2032)
						)
						(arc
							(start -0.3048 0.2032)
							(mid -0.275042 0.275042)
							(end -0.2032 0.3048)
						)
						(arc
							(start 0.2032 0.3048)
							(mid 0.275042 0.275042)
							(end 0.3048 0.2032)
						)
					)
					(width 0)
					(fill yes)
				)
			)
		)
	)
	(footprint ""
		(layer "F.Cu")
		(at 69.215762 -179.460398 180)
		(property "Reference" "C196"
			(at 0 0 180)
			(layer "F.SilkS")
			(hide yes)
			(effects
				(font
					(size 1.27 1.27)
				)
			)
		)
		(property "Value" "SC470P50V2KX-3GP"
			(at 1.1811 -2.7051 180)
			(unlocked yes)
			(layer "F.Fab")
			(hide yes)
			(effects
				(font
					(size 1.016 1.016)
					(thickness 0.1524)
				)
			)
		)
		(property "Device Type" "C402H22"
			(at 1.1811 -4.2291 180)
			(unlocked yes)
			(layer "F.Fab")
			(hide yes)
			(effects
				(font
					(size 1.016 1.016)
					(thickness 0.1524)
				)
			)
		)
		(duplicate_pad_numbers_are_jumpers no)
		(fp_rect
			(start -0.4318 0.9525)
			(end 0.4318 -0.9525)
			(stroke
				(width 0)
				(type default)
			)
			(fill no)
			(layer "F.CrtYd")
		)
		(fp_rect
			(start -0.4318 0.9525)
			(end 0.4318 -0.9525)
			(stroke
				(width 0)
				(type default)
			)
			(fill no)
			(layer "F.Fab")
		)
		(pad "1" smd custom
			(at 0 -0.4445 180)
			(size 0.1524 0.1524)
			(layers "F.Cu" "F.Mask" "F.Paste")
			(net "GND")
			(options
				(clearance outline)
				(anchor circle)
			)
			(primitives
				(gr_poly
					(pts
						(arc
							(start 0.3048 -0.2032)
							(mid 0.275042 -0.275042)
							(end 0.2032 -0.3048)
						)
						(arc
							(start -0.2032 -0.3048)
							(mid -0.275042 -0.275042)
							(end -0.3048 -0.2032)
						)
						(arc
							(start -0.3048 0.2032)
							(mid -0.275042 0.275042)
							(end -0.2032 0.3048)
						)
						(arc
							(start 0.2032 0.3048)
							(mid 0.275042 0.275042)
							(end 0.3048 0.2032)
						)
					)
					(width 0)
					(fill yes)
				)
			)
		)
		(pad "2" smd custom
			(at 0 0.4445 180)
			(size 0.1524 0.1524)
			(layers "F.Cu" "F.Mask" "F.Paste")
			(net "TPS74801_P2V5_STBY_SS")
			(options
				(clearance outline)
				(anchor circle)
			)
			(primitives
				(gr_poly
					(pts
						(arc
							(start 0.3048 -0.2032)
							(mid 0.275042 -0.275042)
							(end 0.2032 -0.3048)
						)
						(arc
							(start -0.2032 -0.3048)
							(mid -0.275042 -0.275042)
							(end -0.3048 -0.2032)
						)
						(arc
							(start -0.3048 0.2032)
							(mid -0.275042 0.275042)
							(end -0.2032 0.3048)
						)
						(arc
							(start 0.2032 0.3048)
							(mid 0.275042 0.275042)
							(end 0.3048 0.2032)
						)
					)
					(width 0)
					(fill yes)
				)
			)
		)
	)
	(footprint ""
		(layer "F.Cu")
		(at 63.443358 -143.019272 90)
		(property "Reference" "R199"
			(at 0 0 90)
			(layer "F.SilkS")
			(hide yes)
			(effects
				(font
					(size 1.27 1.27)
				)
			)
		)
		(property "Value" "1KR2F-3-GP"
			(at 0.064008 -3.993896 90)
			(unlocked yes)
			(layer "F.Fab")
			(hide yes)
			(effects
				(font
					(size 1.016 1.016)
					(thickness 0.1524)
				)
			)
		)
		(property "Device Type" "R402H16"
			(at 0.064008 -5.517896 90)
			(unlocked yes)
			(layer "F.Fab")
			(hide yes)
			(effects
				(font
					(size 1.016 1.016)
					(thickness 0.1524)
				)
			)
		)
		(duplicate_pad_numbers_are_jumpers no)
		(fp_line
			(start 0.508 -0.9398)
			(end -0.508 -0.9398)
			(stroke
				(width 0.1524)
				(type default)
			)
			(layer "F.SilkS")
		)
		(fp_line
			(start -0.508 -0.9398)
			(end -0.508 0.9398)
			(stroke
				(width 0.1524)
				(type default)
			)
			(layer "F.SilkS")
		)
		(fp_rect
			(start -0.508 0.9398)
			(end 0.508 -0.9398)
			(stroke
				(width 0)
				(type default)
			)
			(fill no)
			(layer "F.CrtYd")
		)
		(fp_rect
			(start -0.508 0.9398)
			(end 0.508 -0.9398)
			(stroke
				(width 0)
				(type default)
			)
			(fill no)
			(layer "F.Fab")
		)
		(pad "1" smd custom
			(at 0 -0.4445 90)
			(size 0.1397 0.1397)
			(layers "F.Cu" "F.Mask" "F.Paste")
			(net "I2C_EXP_RMT_SDA_OUT")
			(options
				(clearance outline)
				(anchor circle)
			)
			(primitives
				(gr_poly
					(pts
						(arc
							(start -0.1778 -0.2794)
							(mid -0.249642 -0.249642)
							(end -0.2794 -0.1778)
						)
						(arc
							(start -0.2794 0.1778)
							(mid -0.249642 0.249642)
							(end -0.1778 0.2794)
						)
						(arc
							(start 0.1778 0.2794)
							(mid 0.249642 0.249642)
							(end 0.2794 0.1778)
						)
						(arc
							(start 0.2794 -0.1778)
							(mid 0.249642 -0.249642)
							(end 0.1778 -0.2794)
						)
					)
					(width 0)
					(fill yes)
				)
			)
		)
		(pad "2" smd custom
			(at 0 0.4445 90)
			(size 0.1397 0.1397)
			(layers "F.Cu" "F.Mask" "F.Paste")
			(net "P3V3_STBY")
			(options
				(clearance outline)
				(anchor circle)
			)
			(primitives
				(gr_poly
					(pts
						(arc
							(start -0.1778 -0.2794)
							(mid -0.249642 -0.249642)
							(end -0.2794 -0.1778)
						)
						(arc
							(start -0.2794 0.1778)
							(mid -0.249642 0.249642)
							(end -0.1778 0.2794)
						)
						(arc
							(start 0.1778 0.2794)
							(mid 0.249642 0.249642)
							(end 0.2794 0.1778)
						)
						(arc
							(start 0.2794 -0.1778)
							(mid 0.249642 -0.249642)
							(end 0.1778 -0.2794)
						)
					)
					(width 0)
					(fill yes)
				)
			)
		)
	)
	(footprint ""
		(layer "F.Cu")
		(at 195.407026 -124.154946 90)
		(property "Reference" "R557"
			(at 0 0 90)
			(layer "F.SilkS")
			(hide yes)
			(effects
				(font
					(size 1.27 1.27)
				)
			)
		)
		(property "Value" "1K21R2F-2-GP"
			(at 0.064008 -3.993896 90)
			(unlocked yes)
			(layer "F.Fab")
			(hide yes)
			(effects
				(font
					(size 1.016 1.016)
					(thickness 0.1524)
				)
			)
		)
		(property "Device Type" "R402H16"
			(at 0.064008 -5.517896 90)
			(unlocked yes)
			(layer "F.Fab")
			(hide yes)
			(effects
				(font
					(size 1.016 1.016)
					(thickness 0.1524)
				)
			)
		)
		(duplicate_pad_numbers_are_jumpers no)
		(fp_line
			(start 0.508 -0.9398)
			(end -0.508 -0.9398)
			(stroke
				(width 0.1524)
				(type default)
			)
			(layer "F.SilkS")
		)
		(fp_line
			(start -0.508 -0.9398)
			(end -0.508 0.9398)
			(stroke
				(width 0.1524)
				(type default)
			)
			(layer "F.SilkS")
		)
		(fp_rect
			(start -0.508 0.9398)
			(end 0.508 -0.9398)
			(stroke
				(width 0)
				(type default)
			)
			(fill no)
			(layer "F.CrtYd")
		)
		(fp_rect
			(start -0.508 0.9398)
			(end 0.508 -0.9398)
			(stroke
				(width 0)
				(type default)
			)
			(fill no)
			(layer "F.Fab")
		)
		(pad "1" smd custom
			(at 0 -0.4445 90)
			(size 0.1397 0.1397)
			(layers "F.Cu" "F.Mask" "F.Paste")
			(net "VT235_VFB")
			(options
				(clearance outline)
				(anchor circle)
			)
			(primitives
				(gr_poly
					(pts
						(arc
							(start -0.1778 -0.2794)
							(mid -0.249642 -0.249642)
							(end -0.2794 -0.1778)
						)
						(arc
							(start -0.2794 0.1778)
							(mid -0.249642 0.249642)
							(end -0.1778 0.2794)
						)
						(arc
							(start 0.1778 0.2794)
							(mid 0.249642 0.249642)
							(end 0.2794 0.1778)
						)
						(arc
							(start 0.2794 -0.1778)
							(mid 0.249642 -0.249642)
							(end 0.1778 -0.2794)
						)
					)
					(width 0)
					(fill yes)
				)
			)
		)
		(pad "2" smd custom
			(at 0 0.4445 90)
			(size 0.1397 0.1397)
			(layers "F.Cu" "F.Mask" "F.Paste")
			(net "VT235_VDES_RC")
			(options
				(clearance outline)
				(anchor circle)
			)
			(primitives
				(gr_poly
					(pts
						(arc
							(start -0.1778 -0.2794)
							(mid -0.249642 -0.249642)
							(end -0.2794 -0.1778)
						)
						(arc
							(start -0.2794 0.1778)
							(mid -0.249642 0.249642)
							(end -0.1778 0.2794)
						)
						(arc
							(start 0.1778 0.2794)
							(mid 0.249642 0.249642)
							(end 0.2794 0.1778)
						)
						(arc
							(start 0.2794 -0.1778)
							(mid 0.249642 -0.249642)
							(end 0.1778 -0.2794)
						)
					)
					(width 0)
					(fill yes)
				)
			)
		)
	)
	(footprint ""
		(layer "F.Cu")
		(at 194.9958 -28.702 90)
		(property "Reference" "C515"
			(at 0 0 90)
			(layer "F.SilkS")
			(hide yes)
			(effects
				(font
					(size 1.27 1.27)
				)
			)
		)
		(property "Value" "SCD1U16V2KX-3GP"
			(at 1.1811 -2.7051 90)
			(unlocked yes)
			(layer "F.Fab")
			(hide yes)
			(effects
				(font
					(size 1.016 1.016)
					(thickness 0.1524)
				)
			)
		)
		(property "Device Type" "C402H22"
			(at 1.1811 -4.2291 90)
			(unlocked yes)
			(layer "F.Fab")
			(hide yes)
			(effects
				(font
					(size 1.016 1.016)
					(thickness 0.1524)
				)
			)
		)
		(duplicate_pad_numbers_are_jumpers no)
		(fp_rect
			(start -0.4318 0.9525)
			(end 0.4318 -0.9525)
			(stroke
				(width 0)
				(type default)
			)
			(fill no)
			(layer "F.CrtYd")
		)
		(fp_rect
			(start -0.4318 0.9525)
			(end 0.4318 -0.9525)
			(stroke
				(width 0)
				(type default)
			)
			(fill no)
			(layer "F.Fab")
		)
		(pad "1" smd custom
			(at 0 -0.4445 90)
			(size 0.1524 0.1524)
			(layers "F.Cu" "F.Mask" "F.Paste")
			(net "P1V8")
			(options
				(clearance outline)
				(anchor circle)
			)
			(primitives
				(gr_poly
					(pts
						(arc
							(start 0.3048 -0.2032)
							(mid 0.275042 -0.275042)
							(end 0.2032 -0.3048)
						)
						(arc
							(start -0.2032 -0.3048)
							(mid -0.275042 -0.275042)
							(end -0.3048 -0.2032)
						)
						(arc
							(start -0.3048 0.2032)
							(mid -0.275042 0.275042)
							(end -0.2032 0.3048)
						)
						(arc
							(start 0.2032 0.3048)
							(mid 0.275042 0.275042)
							(end 0.3048 0.2032)
						)
					)
					(width 0)
					(fill yes)
				)
			)
		)
		(pad "2" smd custom
			(at 0 0.4445 90)
			(size 0.1524 0.1524)
			(layers "F.Cu" "F.Mask" "F.Paste")
			(net "GND")
			(options
				(clearance outline)
				(anchor circle)
			)
			(primitives
				(gr_poly
					(pts
						(arc
							(start 0.3048 -0.2032)
							(mid 0.275042 -0.275042)
							(end 0.2032 -0.3048)
						)
						(arc
							(start -0.2032 -0.3048)
							(mid -0.275042 -0.275042)
							(end -0.3048 -0.2032)
						)
						(arc
							(start -0.3048 0.2032)
							(mid -0.275042 0.275042)
							(end -0.2032 0.3048)
						)
						(arc
							(start 0.2032 0.3048)
							(mid 0.275042 0.275042)
							(end 0.3048 0.2032)
						)
					)
					(width 0)
					(fill yes)
				)
			)
		)
	)
	(footprint ""
		(layer "F.Cu")
		(at 96.1009 -148.108924 180)
		(property "Reference" "R34"
			(at 0 0 180)
			(layer "F.SilkS")
			(hide yes)
			(effects
				(font
					(size 1.27 1.27)
				)
			)
		)
		(property "Value" "4K7R2F-GP"
			(at 0.064008 -3.993896 180)
			(unlocked yes)
			(layer "F.Fab")
			(hide yes)
			(effects
				(font
					(size 1.016 1.016)
					(thickness 0.1524)
				)
			)
		)
		(property "Device Type" "R402H16"
			(at 0.064008 -5.517896 180)
			(unlocked yes)
			(layer "F.Fab")
			(hide yes)
			(effects
				(font
					(size 1.016 1.016)
					(thickness 0.1524)
				)
			)
		)
		(duplicate_pad_numbers_are_jumpers no)
		(fp_line
			(start 0.508 -0.9398)
			(end -0.508 -0.9398)
			(stroke
				(width 0.1524)
				(type default)
			)
			(layer "F.SilkS")
		)
		(fp_line
			(start -0.508 -0.9398)
			(end -0.508 0.9398)
			(stroke
				(width 0.1524)
				(type default)
			)
			(layer "F.SilkS")
		)
		(fp_rect
			(start -0.508 0.9398)
			(end 0.508 -0.9398)
			(stroke
				(width 0)
				(type default)
			)
			(fill no)
			(layer "F.CrtYd")
		)
		(fp_rect
			(start -0.508 0.9398)
			(end 0.508 -0.9398)
			(stroke
				(width 0)
				(type default)
			)
			(fill no)
			(layer "F.Fab")
		)
		(pad "1" smd custom
			(at 0 -0.4445 180)
			(size 0.1397 0.1397)
			(layers "F.Cu" "F.Mask" "F.Paste")
			(net "P3V3_STBY")
			(options
				(clearance outline)
				(anchor circle)
			)
			(primitives
				(gr_poly
					(pts
						(arc
							(start -0.1778 -0.2794)
							(mid -0.249642 -0.249642)
							(end -0.2794 -0.1778)
						)
						(arc
							(start -0.2794 0.1778)
							(mid -0.249642 0.249642)
							(end -0.1778 0.2794)
						)
						(arc
							(start 0.1778 0.2794)
							(mid 0.249642 0.249642)
							(end 0.2794 0.1778)
						)
						(arc
							(start 0.2794 -0.1778)
							(mid 0.249642 -0.249642)
							(end 0.1778 -0.2794)
						)
					)
					(width 0)
					(fill yes)
				)
			)
		)
		(pad "2" smd custom
			(at 0 0.4445 180)
			(size 0.1397 0.1397)
			(layers "F.Cu" "F.Mask" "F.Paste")
			(net "USB_EN_2")
			(options
				(clearance outline)
				(anchor circle)
			)
			(primitives
				(gr_poly
					(pts
						(arc
							(start -0.1778 -0.2794)
							(mid -0.249642 -0.249642)
							(end -0.2794 -0.1778)
						)
						(arc
							(start -0.2794 0.1778)
							(mid -0.249642 0.249642)
							(end -0.1778 0.2794)
						)
						(arc
							(start 0.1778 0.2794)
							(mid 0.249642 0.249642)
							(end 0.2794 0.1778)
						)
						(arc
							(start 0.2794 -0.1778)
							(mid 0.249642 -0.249642)
							(end 0.1778 -0.2794)
						)
					)
					(width 0)
					(fill yes)
				)
			)
		)
	)
	(footprint ""
		(layer "F.Cu")
		(at 99.15017 -173.899576 -90)
		(property "Reference" "R124"
			(at 0 0 270)
			(layer "F.SilkS")
			(hide yes)
			(effects
				(font
					(size 1.27 1.27)
				)
			)
		)
		(property "Value" "0R2J-2-GP"
			(at 0.064008 -3.993896 270)
			(unlocked yes)
			(layer "F.Fab")
			(hide yes)
			(effects
				(font
					(size 1.016 1.016)
					(thickness 0.1524)
				)
			)
		)
		(property "Device Type" "R402H16"
			(at 0.064008 -5.517896 270)
			(unlocked yes)
			(layer "F.Fab")
			(hide yes)
			(effects
				(font
					(size 1.016 1.016)
					(thickness 0.1524)
				)
			)
		)
		(duplicate_pad_numbers_are_jumpers no)
		(fp_line
			(start -0.508 -0.9398)
			(end -0.508 0.9398)
			(stroke
				(width 0.1524)
				(type default)
			)
			(layer "F.SilkS")
		)
		(fp_line
			(start 0.508 -0.9398)
			(end -0.508 -0.9398)
			(stroke
				(width 0.1524)
				(type default)
			)
			(layer "F.SilkS")
		)
		(fp_rect
			(start -0.508 0.9398)
			(end 0.508 -0.9398)
			(stroke
				(width 0)
				(type default)
			)
			(fill no)
			(layer "F.CrtYd")
		)
		(fp_rect
			(start -0.508 0.9398)
			(end 0.508 -0.9398)
			(stroke
				(width 0)
				(type default)
			)
			(fill no)
			(layer "F.Fab")
		)
		(pad "1" smd custom
			(at 0 -0.4445 270)
			(size 0.1397 0.1397)
			(layers "F.Cu" "F.Mask" "F.Paste")
			(net "I2C_DPB_MISC_SCL")
			(options
				(clearance outline)
				(anchor circle)
			)
			(primitives
				(gr_poly
					(pts
						(arc
							(start -0.1778 -0.2794)
							(mid -0.249642 -0.249642)
							(end -0.2794 -0.1778)
						)
						(arc
							(start -0.2794 0.1778)
							(mid -0.249642 0.249642)
							(end -0.1778 0.2794)
						)
						(arc
							(start 0.1778 0.2794)
							(mid 0.249642 0.249642)
							(end 0.2794 0.1778)
						)
						(arc
							(start 0.2794 -0.1778)
							(mid 0.249642 -0.249642)
							(end 0.1778 -0.2794)
						)
					)
					(width 0)
					(fill yes)
				)
			)
		)
		(pad "2" smd custom
			(at 0 0.4445 270)
			(size 0.1397 0.1397)
			(layers "F.Cu" "F.Mask" "F.Paste")
			(net "I2C_DPB_MISC_SCL_R")
			(options
				(clearance outline)
				(anchor circle)
			)
			(primitives
				(gr_poly
					(pts
						(arc
							(start -0.1778 -0.2794)
							(mid -0.249642 -0.249642)
							(end -0.2794 -0.1778)
						)
						(arc
							(start -0.2794 0.1778)
							(mid -0.249642 0.249642)
							(end -0.1778 0.2794)
						)
						(arc
							(start 0.1778 0.2794)
							(mid 0.249642 0.249642)
							(end 0.2794 0.1778)
						)
						(arc
							(start 0.2794 -0.1778)
							(mid 0.249642 -0.249642)
							(end 0.1778 -0.2794)
						)
					)
					(width 0)
					(fill yes)
				)
			)
		)
	)
)
